(kicad_pcb
	(version 20241229)
	(generator "pcbnew")
	(generator_version "9.0")
	(general
		(thickness 1.6)
		(legacy_teardrops no)
	)
	(paper "A4")
	(title_block
		(title "OCuLink to PCIe adapter")
		(date "2025-06-18")
		(rev "1.0.0")
		(company "Antmicro Ltd")
		(comment 1 "www.antmicro.com")
		(comment 9 "footprints 96-101 of 159")
	)
	(layers
		(0 "F.Cu" signal)
		(4 "In1.Cu" signal)
		(6 "In2.Cu" signal)
		(2 "B.Cu" signal)
		(9 "F.Adhes" user "F.Adhesive")
		(11 "B.Adhes" user "B.Adhesive")
		(13 "F.Paste" user)
		(15 "B.Paste" user)
		(5 "F.SilkS" user "F.Silkscreen")
		(7 "B.SilkS" user "B.Silkscreen")
		(1 "F.Mask" user)
		(3 "B.Mask" user)
		(17 "Dwgs.User" user "User.Drawings")
		(19 "Cmts.User" user "User.Comments")
		(21 "Eco1.User" user "User.Eco1")
		(23 "Eco2.User" user "User.Eco2")
		(25 "Edge.Cuts" user)
		(27 "Margin" user)
		(31 "F.CrtYd" user "F.Courtyard")
		(29 "B.CrtYd" user "B.Courtyard")
		(35 "F.Fab" user)
		(33 "B.Fab" user)
	)
	(footprint "antmicro-footprints:SC70-3"
		(layer "F.Cu")
		(at 144 41 -90)
		(property "Reference" "D6"
			(at -0.4 1.4 0)
			(layer "F.SilkS")
			(effects
				(font
					(size 0.7 0.7)
					(thickness 0.15)
				)
				(justify right top)
			)
		)
		(property "Value" "TPD2E2U06_SC70"
			(at 0 2.300001 90)
			(layer "F.Fab")
			(effects
				(font
					(size 0.7 0.7)
					(thickness 0.15)
				)
				(justify right top)
			)
		)
		(property "Datasheet" "https://www.ti.com/lit/ds/symlink/tpd2e2u06.pdf?ts=1706006131823&ref_url=https%253A%252F%252Fwww.ti.com%252Finterface%252Fdiodes%252Fesd-protection-diodes%252Fproducts.html"
			(at 0 0 90)
			(layer "F.Fab")
			(hide yes)
			(effects
				(font
					(size 1.27 1.27)
					(thickness 0.15)
				)
			)
		)
		(property "Description" "TVS diode array, 15 kV, SC70, 5.5V, 1.5 pF"
			(at 0 0 90)
			(layer "F.Fab")
			(hide yes)
			(effects
				(font
					(size 1.27 1.27)
					(thickness 0.15)
				)
			)
		)
		(property "MPN" "TPD2E2U06DCKR"
			(at 0 0 270)
			(unlocked yes)
			(layer "F.Fab")
			(hide yes)
			(effects
				(font
					(size 1 1)
					(thickness 0.15)
				)
			)
		)
		(property "Manufacturer" "Texas Instruments"
			(at 0 0 270)
			(unlocked yes)
			(layer "F.Fab")
			(hide yes)
			(effects
				(font
					(size 1 1)
					(thickness 0.15)
				)
			)
		)
		(property "Author" "Antmicro"
			(at 0 0 270)
			(unlocked yes)
			(layer "F.Fab")
			(hide yes)
			(effects
				(font
					(size 1 1)
					(thickness 0.15)
				)
			)
		)
		(property "License" "Apache-2.0"
			(at 0 0 270)
			(unlocked yes)
			(layer "F.Fab")
			(hide yes)
			(effects
				(font
					(size 1 1)
					(thickness 0.15)
				)
			)
		)
		(sheetname "/USB-PD/")
		(sheetfile "usb-pd.kicad_sch")
		(attr smd)
		(fp_line
			(start -0.3 1)
			(end 0.627 1.001)
			(stroke
				(width 0.15)
				(type solid)
			)
			(layer "F.SilkS")
		)
		(fp_line
			(start 0.627 0.6)
			(end 0.627 1.001)
			(stroke
				(width 0.15)
				(type solid)
			)
			(layer "F.SilkS")
		)
		(fp_line
			(start 0.627 -0.6)
			(end 0.627 -0.999)
			(stroke
				(width 0.15)
				(type solid)
			)
			(layer "F.SilkS")
		)
		(fp_line
			(start -0.3 -1)
			(end 0.627 -0.999)
			(stroke
				(width 0.15)
				(type solid)
			)
			(layer "F.SilkS")
		)
		(fp_line
			(start -0.9 1.3)
			(end -0.9 1)
			(stroke
				(width 0.05)
				(type solid)
			)
			(layer "F.CrtYd")
		)
		(fp_line
			(start 0.9 1.3)
			(end -0.9 1.3)
			(stroke
				(width 0.05)
				(type solid)
			)
			(layer "F.CrtYd")
		)
		(fp_line
			(start -1.4 1)
			(end -1.4 -1)
			(stroke
				(width 0.05)
				(type solid)
			)
			(layer "F.CrtYd")
		)
		(fp_line
			(start -0.9 1)
			(end -1.4 1)
			(stroke
				(width 0.05)
				(type solid)
			)
			(layer "F.CrtYd")
		)
		(fp_line
			(start 0.9 0.4)
			(end 0.9 1.3)
			(stroke
				(width 0.05)
				(type solid)
			)
			(layer "F.CrtYd")
		)
		(fp_line
			(start 1.4 0.4)
			(end 0.9 0.4)
			(stroke
				(width 0.05)
				(type solid)
			)
			(layer "F.CrtYd")
		)
		(fp_line
			(start 0.9 -0.4)
			(end 1.4 -0.4)
			(stroke
				(width 0.05)
				(type solid)
			)
			(layer "F.CrtYd")
		)
		(fp_line
			(start 1.4 -0.4)
			(end 1.4 0.4)
			(stroke
				(width 0.05)
				(type solid)
			)
			(layer "F.CrtYd")
		)
		(fp_line
			(start -0.9 -1)
			(end -1.4 -1)
			(stroke
				(width 0.05)
				(type solid)
			)
			(layer "F.CrtYd")
		)
		(fp_line
			(start -0.9 -1.3)
			(end -0.9 -1)
			(stroke
				(width 0.05)
				(type solid)
			)
			(layer "F.CrtYd")
		)
		(fp_line
			(start -0.9 -1.3)
			(end 0.9 -1.3)
			(stroke
				(width 0.05)
				(type solid)
			)
			(layer "F.CrtYd")
		)
		(fp_line
			(start 0.9 -1.3)
			(end 0.9 -0.4)
			(stroke
				(width 0.05)
				(type solid)
			)
			(layer "F.CrtYd")
		)
		(fp_rect
			(start -0.623 -0.999)
			(end 0.627 1.001)
			(stroke
				(width 0.15)
				(type solid)
			)
			(fill no)
			(layer "F.Fab")
		)
		(fp_text user "License: Apache-2.0"
			(at -1.45 6.782 90)
			(layer "F.Fab")
			(effects
				(font
					(size 0.7 0.7)
					(thickness 0.15)
				)
				(justify right top)
			)
		)
		(fp_text user "Author: Antmicro"
			(at -1.45 5.782 90)
			(layer "F.Fab")
			(effects
				(font
					(size 0.7 0.7)
					(thickness 0.15)
				)
				(justify right top)
			)
		)
		(fp_text user "${REFERENCE}"
			(at 0 0 90)
			(layer "F.Fab")
			(effects
				(font
					(size 0.7 0.7)
					(thickness 0.15)
				)
				(justify right top)
			)
		)
		(pad "1" smd rect
			(at -1.051 -0.65)
			(size 0.6 0.6)
			(layers "F.Cu" "F.Mask" "F.Paste")
			(net 140 "/USB-PD/CC1")
			(pinfunction "1")
			(pintype "passive")
		)
		(pad "2" smd rect
			(at -1.051 0.65)
			(size 0.6 0.6)
			(layers "F.Cu" "F.Mask" "F.Paste")
			(net 139 "/USB-PD/CC2")
			(pinfunction "2")
			(pintype "passive")
		)
		(pad "3" smd rect
			(at 1.05 0)
			(size 0.6 0.6)
			(layers "F.Cu" "F.Mask" "F.Paste")
			(net 66 "GND")
			(pinfunction "3")
			(pintype "passive")
		)
	)
	(footprint "antmicro-footprints:R_0402_1005Metric"
		(layer "F.Cu")
		(at 137.85 68.050001 -90)
		(descr "Resistor SMD 0402")
		(tags "resistor SMD 0402")
		(property "Reference" "R49"
			(at 0.900001 4.7995 90)
			(layer "F.SilkS")
			(effects
				(font
					(size 0.7 0.7)
					(thickness 0.15)
				)
				(justify left bottom)
			)
		)
		(property "Value" "R_10k_0402"
			(at -1.011843 1.772046 90)
			(layer "F.Fab")
			(effects
				(font
					(size 0.7 0.7)
					(thickness 0.15)
				)
				(justify right top)
			)
		)
		(property "Datasheet" "https://www.bourns.com/docs/product-datasheets/cr.pdf"
			(at 0 0 90)
			(layer "F.Fab")
			(hide yes)
			(effects
				(font
					(size 1.27 1.27)
					(thickness 0.15)
				)
			)
		)
		(property "Description" "SMD Chip Resistor, 10 kohm, ± 1%, 62.5 mW, 0402 [1005 Metric], Thick Film, General Purpose"
			(at 0 0 90)
			(layer "F.Fab")
			(hide yes)
			(effects
				(font
					(size 1.27 1.27)
					(thickness 0.15)
				)
			)
		)
		(property "MPN" "CR0402-FX-1002GLF"
			(at 0 0 270)
			(unlocked yes)
			(layer "F.Fab")
			(hide yes)
			(effects
				(font
					(size 1 1)
					(thickness 0.15)
				)
			)
		)
		(property "Manufacturer" "Bourns"
			(at 0 0 270)
			(unlocked yes)
			(layer "F.Fab")
			(hide yes)
			(effects
				(font
					(size 1 1)
					(thickness 0.15)
				)
			)
		)
		(property "License" "Apache-2.0"
			(at 0 0 270)
			(unlocked yes)
			(layer "F.Fab")
			(hide yes)
			(effects
				(font
					(size 1 1)
					(thickness 0.15)
				)
			)
		)
		(property "Author" "Antmicro"
			(at 0 0 270)
			(unlocked yes)
			(layer "F.Fab")
			(hide yes)
			(effects
				(font
					(size 1 1)
					(thickness 0.15)
				)
			)
		)
		(property "Val" "10k"
			(at 0 0 270)
			(unlocked yes)
			(layer "F.Fab")
			(hide yes)
			(effects
				(font
					(size 1 1)
					(thickness 0.15)
				)
			)
		)
		(property "Tolerance" "1%"
			(at 0 0 270)
			(unlocked yes)
			(layer "F.Fab")
			(hide yes)
			(effects
				(font
					(size 1 1)
					(thickness 0.15)
				)
			)
		)
		(sheetname "/USB-PD/")
		(sheetfile "usb-pd.kicad_sch")
		(attr smd)
		(fp_rect
			(start -0.925 -0.47)
			(end 0.925 0.47)
			(stroke
				(width 0.05)
				(type default)
			)
			(fill no)
			(layer "F.CrtYd")
		)
		(fp_rect
			(start -0.5 -0.25)
			(end 0.5 0.25)
			(stroke
				(width 0.15)
				(type solid)
			)
			(fill no)
			(layer "F.Fab")
		)
		(fp_text user "License: Apache-2.0"
			(at -0.949999 5.169 90)
			(layer "F.Fab")
			(effects
				(font
					(size 0.7 0.7)
					(thickness 0.15)
				)
				(justify right top)
			)
		)
		(fp_text user "${REFERENCE}"
			(at 0 0 270)
			(layer "F.Fab")
			(effects
				(font
					(size 0.7 0.7)
					(thickness 0.15)
				)
				(justify left bottom)
			)
		)
		(fp_text user "Author: Antmicro"
			(at -0.95 4.169 90)
			(layer "F.Fab")
			(effects
				(font
					(size 0.7 0.7)
					(thickness 0.15)
				)
				(justify right top)
			)
		)
		(pad "1" smd roundrect
			(at -0.48 0 270)
			(size 0.59 0.64)
			(layers "F.Cu" "F.Mask" "F.Paste")
			(roundrect_rratio 0.25)
			(net 66 "GND")
			(pintype "passive")
		)
		(pad "2" smd roundrect
			(at 0.48 0 270)
			(size 0.59 0.64)
			(layers "F.Cu" "F.Mask" "F.Paste")
			(roundrect_rratio 0.25)
			(net 173 "/USB-PD/~{FAULT}")
			(pintype "passive")
		)
	)
	(footprint "antmicro-footprints:TP_Pad0.75mm_Drill0.2mm"
		(layer "F.Cu")
		(at 132.8 94.8 90)
		(property "Reference" "TP13"
			(at -0.45 -3.2 180)
			(layer "F.SilkS")
			(effects
				(font
					(size 0.7 0.7)
					(thickness 0.15)
				)
				(justify left bottom)
			)
		)
		(property "Value" "TP_Pad0.75mm_Drill0.2mm"
			(at 0 1.2 90)
			(layer "F.Fab")
			(effects
				(font
					(size 0.7 0.7)
					(thickness 0.15)
				)
				(justify left bottom)
			)
		)
		(property "Description" "SMT test point"
			(at 0 0 90)
			(layer "F.Fab")
			(hide yes)
			(effects
				(font
					(size 1.27 1.27)
					(thickness 0.15)
				)
			)
		)
		(property "MPN" ""
			(at 0 0 90)
			(unlocked yes)
			(layer "F.Fab")
			(hide yes)
			(effects
				(font
					(size 1 1)
					(thickness 0.15)
				)
			)
		)
		(property "Manufacturer" ""
			(at 0 0 90)
			(unlocked yes)
			(layer "F.Fab")
			(hide yes)
			(effects
				(font
					(size 1 1)
					(thickness 0.15)
				)
			)
		)
		(property "Author" "Antmicro"
			(at 0 0 90)
			(unlocked yes)
			(layer "F.Fab")
			(hide yes)
			(effects
				(font
					(size 1 1)
					(thickness 0.15)
				)
			)
		)
		(property "License" "Apache-2.0"
			(at 0 0 90)
			(unlocked yes)
			(layer "F.Fab")
			(hide yes)
			(effects
				(font
					(size 1 1)
					(thickness 0.15)
				)
			)
		)
		(sheetname "/USB-PD/")
		(sheetfile "usb-pd.kicad_sch")
		(attr exclude_from_pos_files exclude_from_bom)
		(fp_circle
			(center 0 0)
			(end 0.475 0)
			(stroke
				(width 0.05)
				(type default)
			)
			(fill no)
			(layer "F.CrtYd")
		)
		(fp_text user "${REFERENCE}"
			(at -0.4 2.7 90)
			(layer "F.Fab")
			(effects
				(font
					(size 0.7 0.7)
					(thickness 0.15)
				)
				(justify left bottom)
			)
		)
		(fp_text user "Author: Antmicro"
			(at -0.4 3.901 90)
			(layer "F.Fab")
			(effects
				(font
					(size 0.7 0.7)
					(thickness 0.15)
				)
				(justify left bottom)
			)
		)
		(fp_text user "License: Apache-2.0"
			(at -0.4 5.101 90)
			(layer "F.Fab")
			(effects
				(font
					(size 0.7 0.7)
					(thickness 0.15)
				)
				(justify left bottom)
			)
		)
		(pad "1" thru_hole circle
			(at 0 0 90)
			(size 0.75 0.75)
			(drill 0.2)
			(layers "*.Cu" "*.Mask")
			(remove_unused_layers no)
			(net 187 "/USB-PD/12V_CONV")
			(pinfunction "1")
			(pintype "passive")
		)
	)
	(footprint "antmicro-footprints:TP_Pad0.75mm_Drill0.2mm"
		(layer "F.Cu")
		(at 155.75 152)
		(property "Reference" "TP3"
			(at 0.6 0.5 0)
			(layer "F.SilkS")
			(effects
				(font
					(size 0.7 0.7)
					(thickness 0.15)
				)
				(justify left bottom)
			)
		)
		(property "Value" "TP_Pad0.75mm_Drill0.2mm"
			(at 0 1.2 0)
			(layer "F.Fab")
			(effects
				(font
					(size 0.7 0.7)
					(thickness 0.15)
				)
				(justify left bottom)
			)
		)
		(property "Description" "SMT test point"
			(at 0 0 0)
			(layer "F.Fab")
			(hide yes)
			(effects
				(font
					(size 1.27 1.27)
					(thickness 0.15)
				)
			)
		)
		(property "MPN" ""
			(at 0 0 0)
			(unlocked yes)
			(layer "F.Fab")
			(hide yes)
			(effects
				(font
					(size 1 1)
					(thickness 0.15)
				)
			)
		)
		(property "Manufacturer" ""
			(at 0 0 0)
			(unlocked yes)
			(layer "F.Fab")
			(hide yes)
			(effects
				(font
					(size 1 1)
					(thickness 0.15)
				)
			)
		)
		(property "Author" "Antmicro"
			(at 0 0 0)
			(unlocked yes)
			(layer "F.Fab")
			(hide yes)
			(effects
				(font
					(size 1 1)
					(thickness 0.15)
				)
			)
		)
		(property "License" "Apache-2.0"
			(at 0 0 0)
			(unlocked yes)
			(layer "F.Fab")
			(hide yes)
			(effects
				(font
					(size 1 1)
					(thickness 0.15)
				)
			)
		)
		(sheetname "/Power/")
		(sheetfile "power.kicad_sch")
		(attr exclude_from_pos_files exclude_from_bom)
		(fp_circle
			(center 0 0)
			(end 0.475 0)
			(stroke
				(width 0.05)
				(type default)
			)
			(fill no)
			(layer "F.CrtYd")
		)
		(fp_text user "${REFERENCE}"
			(at -0.4 2.7 0)
			(layer "F.Fab")
			(effects
				(font
					(size 0.7 0.7)
					(thickness 0.15)
				)
				(justify left bottom)
			)
		)
		(fp_text user "License: Apache-2.0"
			(at -0.4 5.101 0)
			(layer "F.Fab")
			(effects
				(font
					(size 0.7 0.7)
					(thickness 0.15)
				)
				(justify left bottom)
			)
		)
		(fp_text user "Author: Antmicro"
			(at -0.4 3.901 0)
			(layer "F.Fab")
			(effects
				(font
					(size 0.7 0.7)
					(thickness 0.15)
				)
				(justify left bottom)
			)
		)
		(pad "1" thru_hole circle
			(at 0 0)
			(size 0.75 0.75)
			(drill 0.2)
			(layers "*.Cu" "*.Mask")
			(remove_unused_layers no)
			(net 87 "+12V")
			(pinfunction "1")
			(pintype "passive")
		)
	)
	(footprint "antmicro-footprints:C_0402_1005Metric"
		(layer "F.Cu")
		(at 144.002 95.55 180)
		(descr "Capacitor SMD 0402")
		(tags "capacitor SMD 0402")
		(property "Reference" "C21"
			(at 1.002 0.55 180)
			(layer "F.SilkS")
			(effects
				(font
					(size 0.7 0.7)
					(thickness 0.15)
				)
				(justify right top)
			)
		)
		(property "Value" "C_4u7_25V_0402"
			(at -1.022927 2.155213 0)
			(layer "F.Fab")
			(effects
				(font
					(size 0.7 0.7)
					(thickness 0.15)
				)
				(justify right top)
			)
		)
		(property "Datasheet" "https://www.murata.com/products/productdetail?partno=GRM155C61E475ME15%23"
			(at 0 0 0)
			(layer "F.Fab")
			(hide yes)
			(effects
				(font
					(size 1.27 1.27)
					(thickness 0.15)
				)
			)
		)
		(property "Description" "SMD Multilayer Ceramic Capacitor"
			(at 0 0 0)
			(layer "F.Fab")
			(hide yes)
			(effects
				(font
					(size 1.27 1.27)
					(thickness 0.15)
				)
			)
		)
		(property "MPN" "GRM155C61E475ME15J"
			(at 0 0 180)
			(unlocked yes)
			(layer "F.Fab")
			(hide yes)
			(effects
				(font
					(size 1 1)
					(thickness 0.15)
				)
			)
		)
		(property "Manufacturer" "Murata"
			(at 0 0 180)
			(unlocked yes)
			(layer "F.Fab")
			(hide yes)
			(effects
				(font
					(size 1 1)
					(thickness 0.15)
				)
			)
		)
		(property "License" "Apache-2.0"
			(at 0 0 180)
			(unlocked yes)
			(layer "F.Fab")
			(hide yes)
			(effects
				(font
					(size 1 1)
					(thickness 0.15)
				)
			)
		)
		(property "Author" "Antmicro"
			(at 0 0 180)
			(unlocked yes)
			(layer "F.Fab")
			(hide yes)
			(effects
				(font
					(size 1 1)
					(thickness 0.15)
				)
			)
		)
		(property "Val" "4u7"
			(at 0 0 180)
			(unlocked yes)
			(layer "F.Fab")
			(hide yes)
			(effects
				(font
					(size 1 1)
					(thickness 0.15)
				)
			)
		)
		(property "Voltage" "25V"
			(at 0 0 180)
			(unlocked yes)
			(layer "F.Fab")
			(hide yes)
			(effects
				(font
					(size 1 1)
					(thickness 0.15)
				)
			)
		)
		(property "Dielectric" "X5S"
			(at 0 0 180)
			(unlocked yes)
			(layer "F.Fab")
			(hide yes)
			(effects
				(font
					(size 1 1)
					(thickness 0.15)
				)
			)
		)
		(sheetname "/USB-PD/")
		(sheetfile "usb-pd.kicad_sch")
		(attr smd)
		(fp_rect
			(start -0.925 -0.47)
			(end 0.925 0.47)
			(stroke
				(width 0.05)
				(type default)
			)
			(fill no)
			(layer "F.CrtYd")
		)
		(fp_line
			(start 0.504 0.248)
			(end -0.494 0.248)
			(stroke
				(width 0.15)
				(type solid)
			)
			(layer "F.Fab")
		)
		(fp_line
			(start 0.504 -0.25)
			(end 0.504 0.248)
			(stroke
				(width 0.15)
				(type solid)
			)
			(layer "F.Fab")
		)
		(fp_line
			(start -0.494 0.248)
			(end -0.494 -0.25)
			(stroke
				(width 0.15)
				(type solid)
			)
			(layer "F.Fab")
		)
		(fp_line
			(start -0.494 -0.25)
			(end 0.504 -0.25)
			(stroke
				(width 0.15)
				(type solid)
			)
			(layer "F.Fab")
		)
		(fp_text user "Author: Antmicro"
			(at -0.939 3.399 0)
			(layer "F.Fab")
			(effects
				(font
					(size 0.7 0.7)
					(thickness 0.15)
				)
				(justify right top)
			)
		)
		(fp_text user "License: Apache-2.0"
			(at -0.939 5.799 0)
			(layer "F.Fab")
			(effects
				(font
					(size 0.7 0.7)
					(thickness 0.15)
				)
				(justify right top)
			)
		)
		(fp_text user "${REFERENCE}"
			(at 0 0 0)
			(layer "F.Fab")
			(effects
				(font
					(size 0.7 0.7)
					(thickness 0.15)
				)
				(justify right top)
			)
		)
		(pad "1" smd roundrect
			(at -0.48 0 180)
			(size 0.59 0.64)
			(layers "F.Cu" "F.Mask" "F.Paste")
			(roundrect_rratio 0.25)
			(net 66 "GND")
			(pintype "passive")
		)
		(pad "2" smd roundrect
			(at 0.48 0 180)
			(size 0.59 0.64)
			(layers "F.Cu" "F.Mask" "F.Paste")
			(roundrect_rratio 0.25)
			(net 123 "/USB-PD/12V_VDRV")
			(pintype "passive")
		)
	)
	(footprint "antmicro-footprints:MP_Pad6mm_Drill3.2mm"
		(layer "F.Cu")
		(at 104.8 162.8 -90)
		(property "Reference" "MP4"
			(at 0 0 90)
			(layer "F.SilkS")
			(hide yes)
			(effects
				(font
					(size 0.7 0.7)
					(thickness 0.15)
				)
				(justify right top)
			)
		)
		(property "Value" "MP_Pad6mm_Drill3.2mm"
			(at 0 3.899999 90)
			(layer "F.Fab")
			(effects
				(font
					(size 0.7 0.7)
					(thickness 0.15)
				)
				(justify right top)
			)
		)
		(property "Description" "Mechanical part"
			(at 0 0 90)
			(layer "F.Fab")
			(hide yes)
			(effects
				(font
					(size 1.27 1.27)
					(thickness 0.15)
				)
			)
		)
		(property "Author" "Antmicro"
			(at 0 0 270)
			(unlocked yes)
			(layer "F.Fab")
			(hide yes)
			(effects
				(font
					(size 1 1)
					(thickness 0.15)
				)
			)
		)
		(property "License" "Apache-2.0"
			(at 0 0 270)
			(unlocked yes)
			(layer "F.Fab")
			(hide yes)
			(effects
				(font
					(size 1 1)
					(thickness 0.15)
				)
			)
		)
		(sheetname "/")
		(sheetfile "oculink-to-pcie-adapter.kicad_sch")
		(attr exclude_from_pos_files exclude_from_bom)
		(fp_circle
			(center 0 0)
			(end 3.25 0)
			(stroke
				(width 0.05)
				(type default)
			)
			(fill no)
			(layer "F.CrtYd")
		)
		(fp_text user "Author: Antmicro"
			(at -0.178001 7.225 90)
			(layer "F.Fab")
			(effects
				(font
					(size 0.7 0.7)
					(thickness 0.15)
				)
				(justify right top)
			)
		)
		(fp_text user "${REFERENCE}"
			(at 0 0 90)
			(layer "F.Fab")
			(effects
				(font
					(size 0.7 0.7)
					(thickness 0.15)
				)
				(justify right top)
			)
		)
		(fp_text user "License: Apache-2.0"
			(at -0.178 8.425001 90)
			(layer "F.Fab")
			(effects
				(font
					(size 0.7 0.7)
					(thickness 0.15)
				)
				(justify right top)
			)
		)
		(pad "1" thru_hole circle
			(at 0 0 270)
			(size 6 6)
			(drill 3.2)
			(layers "*.Cu" "*.Mask")
			(remove_unused_layers no)
			(net 66 "GND")
			(pintype "passive")
		)
	)
)
